(kicad_pcb
	(version 20260206)
	(generator "pcbnew")
	(generator_version "10.0")
	(general
		(thickness 1.6)
		(legacy_teardrops no)
	)
	(paper "A4")
	(title_block
		(title "01162023_DA0F0TEBIF0_F0T_Expander_BD_F_brd_V02_OCP.brd")
		(comment 1 "Grand Teton / footprints 6282-6288 of 9728")
	)
	(layers
		(0 "F.Cu" signal "TOP")
		(4 "In1.Cu" signal "GND")
		(6 "In2.Cu" signal "VCC")
		(8 "In3.Cu" signal "VCC1")
		(10 "In4.Cu" signal "GND1")
		(12 "In5.Cu" signal "IN1")
		(14 "In6.Cu" signal "GND2")
		(16 "In7.Cu" signal "IN2")
		(18 "In8.Cu" signal "GND3")
		(20 "In9.Cu" signal "IN3")
		(22 "In10.Cu" signal "GND4")
		(24 "In11.Cu" signal "IN4")
		(26 "In12.Cu" signal "GND5")
		(28 "In13.Cu" signal "IN5")
		(30 "In14.Cu" signal "GND6")
		(32 "In15.Cu" signal "IN6")
		(34 "In16.Cu" signal "GND7")
		(2 "B.Cu" signal "BOTTOM")
		(9 "F.Adhes" user "F.Adhesive")
		(11 "B.Adhes" user "B.Adhesive")
		(13 "F.Paste" user "Package Geometry/Pastemask Top")
		(15 "B.Paste" user "Package Geometry/Pastemask Bottom")
		(5 "F.SilkS" user "Ref Des/Silkscreen Top")
		(7 "B.SilkS" user "Ref Des/Silkscreen Bottom")
		(1 "F.Mask" user "Board Geometry/Soldermask Top")
		(3 "B.Mask" user "Board Geometry/Soldermask Bottom")
		(17 "Dwgs.User" user "User.Drawings")
		(19 "Cmts.User" user "User.Comments")
		(21 "Eco1.User" user "User.Eco1")
		(23 "Eco2.User" user "User.Eco2")
		(25 "Edge.Cuts" user "Board Geometry/Outline")
		(27 "Margin" user)
		(31 "F.CrtYd" user "Package Geometry/Place Bound Top")
		(29 "B.CrtYd" user "Package Geometry/Place Bound Bottom")
		(35 "F.Fab" user "Ref Des/Assembly Top")
		(33 "B.Fab" user "Ref Des/Assembly Bottom")
	)
	(footprint ""
		(layer "F.Cu")
		(at 141.162532 -22.955504 -90)
		(property "Reference" "C2719"
			(at 0 0 270)
			(layer "F.SilkS")
			(hide yes)
			(effects
				(font
					(size 1.27 1.27)
				)
			)
		)
		(property "Value" ""
			(at 0 0 270)
			(layer "F.Fab")
			(effects
				(font
					(size 1.27 1.27)
				)
			)
		)
		(duplicate_pad_numbers_are_jumpers no)
		(fp_line
			(start -0.7874 0.4064)
			(end -0.7874 -0.4064)
			(stroke
				(width 0.1524)
				(type default)
			)
			(layer "F.SilkS")
		)
		(fp_line
			(start 0.7874 0.4064)
			(end -0.7874 0.4064)
			(stroke
				(width 0.1524)
				(type default)
			)
			(layer "F.SilkS")
		)
		(fp_line
			(start -0.7874 -0.4064)
			(end 0.7874 -0.4064)
			(stroke
				(width 0.1524)
				(type default)
			)
			(layer "F.SilkS")
		)
		(fp_line
			(start 0.7874 -0.4064)
			(end 0.7874 0.4064)
			(stroke
				(width 0.1524)
				(type default)
			)
			(layer "F.SilkS")
		)
		(fp_line
			(start -0.67945 0.3048)
			(end -0.67945 -0.305054)
			(stroke
				(width 0.1)
				(type default)
			)
			(layer "F.Fab")
		)
		(fp_line
			(start -0.12065 0.3048)
			(end -0.67945 0.3048)
			(stroke
				(width 0.1)
				(type default)
			)
			(layer "F.Fab")
		)
		(fp_line
			(start 0.120396 0.3048)
			(end 0.120396 0.2794)
			(stroke
				(width 0.1)
				(type default)
			)
			(layer "F.Fab")
		)
		(fp_line
			(start 0.67945 0.3048)
			(end 0.120396 0.3048)
			(stroke
				(width 0.1)
				(type default)
			)
			(layer "F.Fab")
		)
		(fp_line
			(start -0.12065 0.2794)
			(end -0.12065 0.3048)
			(stroke
				(width 0.1)
				(type default)
			)
			(layer "F.Fab")
		)
		(fp_line
			(start 0.120396 0.2794)
			(end -0.12065 0.2794)
			(stroke
				(width 0.1)
				(type default)
			)
			(layer "F.Fab")
		)
		(fp_line
			(start -0.12065 -0.2794)
			(end 0.12065 -0.2794)
			(stroke
				(width 0.1)
				(type default)
			)
			(layer "F.Fab")
		)
		(fp_line
			(start 0.12065 -0.2794)
			(end 0.12065 -0.3048)
			(stroke
				(width 0.1)
				(type default)
			)
			(layer "F.Fab")
		)
		(fp_line
			(start 0.12065 -0.3048)
			(end 0.67945 -0.3048)
			(stroke
				(width 0.1)
				(type default)
			)
			(layer "F.Fab")
		)
		(fp_line
			(start 0.67945 -0.3048)
			(end 0.67945 0.3048)
			(stroke
				(width 0.1)
				(type default)
			)
			(layer "F.Fab")
		)
		(fp_line
			(start -0.67945 -0.305054)
			(end -0.12065 -0.305054)
			(stroke
				(width 0.1)
				(type default)
			)
			(layer "F.Fab")
		)
		(fp_line
			(start -0.12065 -0.305054)
			(end -0.12065 -0.2794)
			(stroke
				(width 0.1)
				(type default)
			)
			(layer "F.Fab")
		)
		(pad "1" smd circle
			(at -0.40005 0 270)
			(size 0 0)
			(layers "F.Cu" "F.Mask" "F.Paste")
			(net "GND")
		)
		(pad "2" smd circle
			(at 0.40005 0 270)
			(size 0 0)
			(layers "F.Cu" "F.Mask" "F.Paste")
			(net "P3V3_AUX")
		)
	)
	(footprint ""
		(layer "F.Cu")
		(at 426.75937 -22.955504 90)
		(property "Reference" "R1741"
			(at 0 0 90)
			(layer "F.SilkS")
			(hide yes)
			(effects
				(font
					(size 1.27 1.27)
				)
			)
		)
		(property "Value" ""
			(at 0 0 90)
			(layer "F.Fab")
			(effects
				(font
					(size 1.27 1.27)
				)
			)
		)
		(duplicate_pad_numbers_are_jumpers no)
		(fp_line
			(start 0.7874 -0.4064)
			(end 0.7874 0.4064)
			(stroke
				(width 0.1524)
				(type default)
			)
			(layer "F.SilkS")
		)
		(fp_line
			(start -0.7874 -0.4064)
			(end 0.7874 -0.4064)
			(stroke
				(width 0.1524)
				(type default)
			)
			(layer "F.SilkS")
		)
		(fp_line
			(start 0.7874 0.4064)
			(end -0.7874 0.4064)
			(stroke
				(width 0.1524)
				(type default)
			)
			(layer "F.SilkS")
		)
		(fp_line
			(start -0.7874 0.4064)
			(end -0.7874 -0.4064)
			(stroke
				(width 0.1524)
				(type default)
			)
			(layer "F.SilkS")
		)
		(fp_line
			(start -0.12065 -0.305054)
			(end -0.12065 -0.2794)
			(stroke
				(width 0.1)
				(type default)
			)
			(layer "F.Fab")
		)
		(fp_line
			(start -0.67945 -0.305054)
			(end -0.12065 -0.305054)
			(stroke
				(width 0.1)
				(type default)
			)
			(layer "F.Fab")
		)
		(fp_line
			(start 0.67945 -0.3048)
			(end 0.67945 0.3048)
			(stroke
				(width 0.1)
				(type default)
			)
			(layer "F.Fab")
		)
		(fp_line
			(start 0.12065 -0.3048)
			(end 0.67945 -0.3048)
			(stroke
				(width 0.1)
				(type default)
			)
			(layer "F.Fab")
		)
		(fp_line
			(start 0.12065 -0.2794)
			(end 0.12065 -0.3048)
			(stroke
				(width 0.1)
				(type default)
			)
			(layer "F.Fab")
		)
		(fp_line
			(start -0.12065 -0.2794)
			(end 0.12065 -0.2794)
			(stroke
				(width 0.1)
				(type default)
			)
			(layer "F.Fab")
		)
		(fp_line
			(start 0.120396 0.2794)
			(end -0.12065 0.2794)
			(stroke
				(width 0.1)
				(type default)
			)
			(layer "F.Fab")
		)
		(fp_line
			(start -0.12065 0.2794)
			(end -0.12065 0.3048)
			(stroke
				(width 0.1)
				(type default)
			)
			(layer "F.Fab")
		)
		(fp_line
			(start 0.67945 0.3048)
			(end 0.120396 0.3048)
			(stroke
				(width 0.1)
				(type default)
			)
			(layer "F.Fab")
		)
		(fp_line
			(start 0.120396 0.3048)
			(end 0.120396 0.2794)
			(stroke
				(width 0.1)
				(type default)
			)
			(layer "F.Fab")
		)
		(fp_line
			(start -0.12065 0.3048)
			(end -0.67945 0.3048)
			(stroke
				(width 0.1)
				(type default)
			)
			(layer "F.Fab")
		)
		(fp_line
			(start -0.67945 0.3048)
			(end -0.67945 -0.305054)
			(stroke
				(width 0.1)
				(type default)
			)
			(layer "F.Fab")
		)
		(pad "1" smd circle
			(at -0.40005 0 90)
			(size 0 0)
			(layers "F.Cu" "F.Mask" "F.Paste")
			(net "SMB_BIC_I2C9_MUX1_SSD14_R_SCL")
		)
		(pad "2" smd circle
			(at 0.40005 0 90)
			(size 0 0)
			(layers "F.Cu" "F.Mask" "F.Paste")
			(net "SMB_ISO_SSD14_SCL")
		)
	)
	(footprint ""
		(layer "F.Cu")
		(at 100.820474 -70.307454 90)
		(property "Reference" "PC638"
			(at 0 0 90)
			(layer "F.SilkS")
			(hide yes)
			(effects
				(font
					(size 1.27 1.27)
				)
			)
		)
		(property "Value" ""
			(at 0 0 90)
			(layer "F.Fab")
			(effects
				(font
					(size 1.27 1.27)
				)
			)
		)
		(duplicate_pad_numbers_are_jumpers no)
		(fp_line
			(start 0.7874 -0.4064)
			(end 0.7874 0.4064)
			(stroke
				(width 0.1524)
				(type default)
			)
			(layer "F.SilkS")
		)
		(fp_line
			(start -0.7874 -0.4064)
			(end 0.7874 -0.4064)
			(stroke
				(width 0.1524)
				(type default)
			)
			(layer "F.SilkS")
		)
		(fp_line
			(start 0.7874 0.4064)
			(end -0.7874 0.4064)
			(stroke
				(width 0.1524)
				(type default)
			)
			(layer "F.SilkS")
		)
		(fp_line
			(start -0.7874 0.4064)
			(end -0.7874 -0.4064)
			(stroke
				(width 0.1524)
				(type default)
			)
			(layer "F.SilkS")
		)
		(fp_line
			(start -0.12065 -0.305054)
			(end -0.12065 -0.2794)
			(stroke
				(width 0.1)
				(type default)
			)
			(layer "F.Fab")
		)
		(fp_line
			(start -0.67945 -0.305054)
			(end -0.12065 -0.305054)
			(stroke
				(width 0.1)
				(type default)
			)
			(layer "F.Fab")
		)
		(fp_line
			(start 0.67945 -0.3048)
			(end 0.67945 0.3048)
			(stroke
				(width 0.1)
				(type default)
			)
			(layer "F.Fab")
		)
		(fp_line
			(start 0.12065 -0.3048)
			(end 0.67945 -0.3048)
			(stroke
				(width 0.1)
				(type default)
			)
			(layer "F.Fab")
		)
		(fp_line
			(start 0.12065 -0.2794)
			(end 0.12065 -0.3048)
			(stroke
				(width 0.1)
				(type default)
			)
			(layer "F.Fab")
		)
		(fp_line
			(start -0.12065 -0.2794)
			(end 0.12065 -0.2794)
			(stroke
				(width 0.1)
				(type default)
			)
			(layer "F.Fab")
		)
		(fp_line
			(start 0.120396 0.2794)
			(end -0.12065 0.2794)
			(stroke
				(width 0.1)
				(type default)
			)
			(layer "F.Fab")
		)
		(fp_line
			(start -0.12065 0.2794)
			(end -0.12065 0.3048)
			(stroke
				(width 0.1)
				(type default)
			)
			(layer "F.Fab")
		)
		(fp_line
			(start 0.67945 0.3048)
			(end 0.120396 0.3048)
			(stroke
				(width 0.1)
				(type default)
			)
			(layer "F.Fab")
		)
		(fp_line
			(start 0.120396 0.3048)
			(end 0.120396 0.2794)
			(stroke
				(width 0.1)
				(type default)
			)
			(layer "F.Fab")
		)
		(fp_line
			(start -0.12065 0.3048)
			(end -0.67945 0.3048)
			(stroke
				(width 0.1)
				(type default)
			)
			(layer "F.Fab")
		)
		(fp_line
			(start -0.67945 0.3048)
			(end -0.67945 -0.305054)
			(stroke
				(width 0.1)
				(type default)
			)
			(layer "F.Fab")
		)
		(pad "1" smd circle
			(at -0.40005 0 90)
			(size 0 0)
			(layers "F.Cu" "F.Mask" "F.Paste")
			(net "P12V_AUX")
		)
		(pad "2" smd circle
			(at 0.40005 0 90)
			(size 0 0)
			(layers "F.Cu" "F.Mask" "F.Paste")
			(net "GND")
		)
	)
	(footprint ""
		(layer "F.Cu")
		(at 152.738328 -112.809782)
		(property "Reference" "C261"
			(at 0 0 0)
			(layer "F.SilkS")
			(hide yes)
			(effects
				(font
					(size 1.27 1.27)
				)
			)
		)
		(property "Value" ""
			(at 0 0 0)
			(layer "F.Fab")
			(effects
				(font
					(size 1.27 1.27)
				)
			)
		)
		(duplicate_pad_numbers_are_jumpers no)
		(fp_line
			(start -0.299974 -0.150114)
			(end 0.299974 -0.150114)
			(stroke
				(width 0.1)
				(type default)
			)
			(layer "F.Fab")
		)
		(fp_line
			(start -0.299974 0.150114)
			(end -0.299974 -0.150114)
			(stroke
				(width 0.1)
				(type default)
			)
			(layer "F.Fab")
		)
		(fp_line
			(start 0.299974 -0.150114)
			(end 0.299974 0.150114)
			(stroke
				(width 0.1)
				(type default)
			)
			(layer "F.Fab")
		)
		(fp_line
			(start 0.299974 0.150114)
			(end -0.299974 0.150114)
			(stroke
				(width 0.1)
				(type default)
			)
			(layer "F.Fab")
		)
		(pad "1" smd rect
			(at -0.2667 0)
			(size 0.3048 0.381)
			(layers "F.Cu" "F.Mask" "F.Paste")
			(net "P5E_PEX1_STN1_TX_DP<23>")
		)
		(pad "2" smd rect
			(at 0.2667 0)
			(size 0.3048 0.381)
			(layers "F.Cu" "F.Mask" "F.Paste")
			(net "P5E_PEX1_STN1_TX_C_DP<23>")
		)
	)
	(footprint ""
		(layer "F.Cu")
		(at 363.474 -211.963 180)
		(property "Reference" "R4611"
			(at 0 0 180)
			(layer "F.SilkS")
			(hide yes)
			(effects
				(font
					(size 1.27 1.27)
				)
			)
		)
		(property "Value" ""
			(at 0 0 180)
			(layer "F.Fab")
			(effects
				(font
					(size 1.27 1.27)
				)
			)
		)
		(duplicate_pad_numbers_are_jumpers no)
		(fp_line
			(start 0.7874 0.4064)
			(end -0.7874 0.4064)
			(stroke
				(width 0.1524)
				(type default)
			)
			(layer "F.SilkS")
		)
		(fp_line
			(start 0.7874 -0.4064)
			(end 0.7874 0.4064)
			(stroke
				(width 0.1524)
				(type default)
			)
			(layer "F.SilkS")
		)
		(fp_line
			(start -0.7874 0.4064)
			(end -0.7874 -0.4064)
			(stroke
				(width 0.1524)
				(type default)
			)
			(layer "F.SilkS")
		)
		(fp_line
			(start -0.7874 -0.4064)
			(end 0.7874 -0.4064)
			(stroke
				(width 0.1524)
				(type default)
			)
			(layer "F.SilkS")
		)
		(fp_line
			(start 0.67945 0.3048)
			(end 0.120396 0.3048)
			(stroke
				(width 0.1)
				(type default)
			)
			(layer "F.Fab")
		)
		(fp_line
			(start 0.67945 -0.3048)
			(end 0.67945 0.3048)
			(stroke
				(width 0.1)
				(type default)
			)
			(layer "F.Fab")
		)
		(fp_line
			(start 0.12065 -0.2794)
			(end 0.12065 -0.3048)
			(stroke
				(width 0.1)
				(type default)
			)
			(layer "F.Fab")
		)
		(fp_line
			(start 0.12065 -0.3048)
			(end 0.67945 -0.3048)
			(stroke
				(width 0.1)
				(type default)
			)
			(layer "F.Fab")
		)
		(fp_line
			(start 0.120396 0.3048)
			(end 0.120396 0.2794)
			(stroke
				(width 0.1)
				(type default)
			)
			(layer "F.Fab")
		)
		(fp_line
			(start 0.120396 0.2794)
			(end -0.12065 0.2794)
			(stroke
				(width 0.1)
				(type default)
			)
			(layer "F.Fab")
		)
		(fp_line
			(start -0.12065 0.3048)
			(end -0.67945 0.3048)
			(stroke
				(width 0.1)
				(type default)
			)
			(layer "F.Fab")
		)
		(fp_line
			(start -0.12065 0.2794)
			(end -0.12065 0.3048)
			(stroke
				(width 0.1)
				(type default)
			)
			(layer "F.Fab")
		)
		(fp_line
			(start -0.12065 -0.2794)
			(end 0.12065 -0.2794)
			(stroke
				(width 0.1)
				(type default)
			)
			(layer "F.Fab")
		)
		(fp_line
			(start -0.12065 -0.305054)
			(end -0.12065 -0.2794)
			(stroke
				(width 0.1)
				(type default)
			)
			(layer "F.Fab")
		)
		(fp_line
			(start -0.67945 0.3048)
			(end -0.67945 -0.305054)
			(stroke
				(width 0.1)
				(type default)
			)
			(layer "F.Fab")
		)
		(fp_line
			(start -0.67945 -0.305054)
			(end -0.12065 -0.305054)
			(stroke
				(width 0.1)
				(type default)
			)
			(layer "F.Fab")
		)
		(pad "1" smd circle
			(at -0.40005 0 180)
			(size 0 0)
			(layers "F.Cu" "F.Mask" "F.Paste")
			(net "SSD0_PEX_PWR_EN_R")
		)
		(pad "2" smd circle
			(at 0.40005 0 180)
			(size 0 0)
			(layers "F.Cu" "F.Mask" "F.Paste")
			(net "GND")
		)
	)
	(footprint ""
		(layer "F.Cu")
		(at 73.28281 -80.739742)
		(property "Reference" "R101"
			(at 0 0 0)
			(layer "F.SilkS")
			(hide yes)
			(effects
				(font
					(size 1.27 1.27)
				)
			)
		)
		(property "Value" ""
			(at 0 0 0)
			(layer "F.Fab")
			(effects
				(font
					(size 1.27 1.27)
				)
			)
		)
		(duplicate_pad_numbers_are_jumpers no)
		(fp_line
			(start -0.7874 -0.4064)
			(end 0.7874 -0.4064)
			(stroke
				(width 0.1524)
				(type default)
			)
			(layer "F.SilkS")
		)
		(fp_line
			(start -0.7874 0.4064)
			(end -0.7874 -0.4064)
			(stroke
				(width 0.1524)
				(type default)
			)
			(layer "F.SilkS")
		)
		(fp_line
			(start 0.7874 -0.4064)
			(end 0.7874 0.4064)
			(stroke
				(width 0.1524)
				(type default)
			)
			(layer "F.SilkS")
		)
		(fp_line
			(start 0.7874 0.4064)
			(end -0.7874 0.4064)
			(stroke
				(width 0.1524)
				(type default)
			)
			(layer "F.SilkS")
		)
		(fp_line
			(start -0.67945 -0.305054)
			(end -0.12065 -0.305054)
			(stroke
				(width 0.1)
				(type default)
			)
			(layer "F.Fab")
		)
		(fp_line
			(start -0.67945 0.3048)
			(end -0.67945 -0.305054)
			(stroke
				(width 0.1)
				(type default)
			)
			(layer "F.Fab")
		)
		(fp_line
			(start -0.12065 -0.305054)
			(end -0.12065 -0.2794)
			(stroke
				(width 0.1)
				(type default)
			)
			(layer "F.Fab")
		)
		(fp_line
			(start -0.12065 -0.2794)
			(end 0.12065 -0.2794)
			(stroke
				(width 0.1)
				(type default)
			)
			(layer "F.Fab")
		)
		(fp_line
			(start -0.12065 0.2794)
			(end -0.12065 0.3048)
			(stroke
				(width 0.1)
				(type default)
			)
			(layer "F.Fab")
		)
		(fp_line
			(start -0.12065 0.3048)
			(end -0.67945 0.3048)
			(stroke
				(width 0.1)
				(type default)
			)
			(layer "F.Fab")
		)
		(fp_line
			(start 0.120396 0.2794)
			(end -0.12065 0.2794)
			(stroke
				(width 0.1)
				(type default)
			)
			(layer "F.Fab")
		)
		(fp_line
			(start 0.120396 0.3048)
			(end 0.120396 0.2794)
			(stroke
				(width 0.1)
				(type default)
			)
			(layer "F.Fab")
		)
		(fp_line
			(start 0.12065 -0.3048)
			(end 0.67945 -0.3048)
			(stroke
				(width 0.1)
				(type default)
			)
			(layer "F.Fab")
		)
		(fp_line
			(start 0.12065 -0.2794)
			(end 0.12065 -0.3048)
			(stroke
				(width 0.1)
				(type default)
			)
			(layer "F.Fab")
		)
		(fp_line
			(start 0.67945 -0.3048)
			(end 0.67945 0.3048)
			(stroke
				(width 0.1)
				(type default)
			)
			(layer "F.Fab")
		)
		(fp_line
			(start 0.67945 0.3048)
			(end 0.120396 0.3048)
			(stroke
				(width 0.1)
				(type default)
			)
			(layer "F.Fab")
		)
		(pad "1" smd circle
			(at -0.40005 0)
			(size 0 0)
			(layers "F.Cu" "F.Mask" "F.Paste")
			(net "P3V3_AUX")
		)
		(pad "2" smd circle
			(at 0.40005 0)
			(size 0 0)
			(layers "F.Cu" "F.Mask" "F.Paste")
			(net "HP_NIC1_HSC_PWRGD_N")
		)
	)
	(footprint ""
		(layer "F.Cu")
		(at 431.950114 -50.96383 180)
		(property "Reference" "PC584"
			(at 0 0 180)
			(layer "F.SilkS")
			(hide yes)
			(effects
				(font
					(size 1.27 1.27)
				)
			)
		)
		(property "Value" ""
			(at 0 0 180)
			(layer "F.Fab")
			(effects
				(font
					(size 1.27 1.27)
				)
			)
		)
		(duplicate_pad_numbers_are_jumpers no)
		(fp_line
			(start 1.524 0.762)
			(end -1.524 0.762)
			(stroke
				(width 0.1524)
				(type default)
			)
			(layer "F.SilkS")
		)
		(fp_line
			(start 1.524 -0.762)
			(end 1.524 0.762)
			(stroke
				(width 0.1524)
				(type default)
			)
			(layer "F.SilkS")
		)
		(fp_line
			(start -1.524 0.762)
			(end -1.524 -0.762)
			(stroke
				(width 0.1524)
				(type default)
			)
			(layer "F.SilkS")
		)
		(fp_line
			(start -1.524 -0.762)
			(end 1.524 -0.762)
			(stroke
				(width 0.1524)
				(type default)
			)
			(layer "F.SilkS")
		)
		(fp_line
			(start 1.1049 0.724916)
			(end 1.1049 -0.724916)
			(stroke
				(width 0.1)
				(type default)
			)
			(layer "F.Fab")
		)
		(fp_line
			(start 1.1049 -0.724916)
			(end -1.1049 -0.724916)
			(stroke
				(width 0.1)
				(type default)
			)
			(layer "F.Fab")
		)
		(fp_line
			(start -1.1049 0.724916)
			(end 1.1049 0.724916)
			(stroke
				(width 0.1)
				(type default)
			)
			(layer "F.Fab")
		)
		(fp_line
			(start -1.1049 -0.724916)
			(end -1.1049 0.724916)
			(stroke
				(width 0.1)
				(type default)
			)
			(layer "F.Fab")
		)
		(pad "1" smd rect
			(at -0.889 0)
			(size 1.016 1.27)
			(layers "F.Cu" "F.Mask" "F.Paste")
			(net "P3V3_SSD15")
		)
		(pad "2" smd rect
			(at 0.889 0)
			(size 1.016 1.27)
			(layers "F.Cu" "F.Mask" "F.Paste")
			(net "GND")
		)
	)
)
